FILE_TYPE = CONNECTIVITY;
{Allegro Design Entry HDL 17.2-2016 S081 (4005846) 1/11/2022}
"PAGE_NUMBER" = 11;
0"NC";
1"M_B_CPU0_SA_DQ<31:0>";
2"M_B_CPU0_SB_DQ<31:0>";
3"M_B_CPU0_SA_CB<7:0>";
4"M_B_CPU0_SB_CB<7:0>";
5"M_B_CPU0_SA_DQS_DP<9:0>";
6"M_B_CPU0_SB_DQS_DP<9:0>";
7"M_B_CPU0_SA_CA<6:0>";
8"M_B_CPU0_SB_CA<6:0>";
9"M_B_CPU0_SA_DQS_DN<9:0>";
10"M_B_CPU0_SB_DQS_DN<9:0>";
11"M_B_CPU0_ALERT_N";
12"TP_M_B_CPU0_SA_TEST39B";
13"M_B_CPU0_ALERT_R_N";
14"M_B_CPU0_CLK_DP<0>";
15"M_B_CPU0_CLK_DN<0>";
16"M_B_CPU0_SA_CS_N<0>";
17"M_B_CPU0_SA_CS_N<1>";
18"M_B_CPU0_SA_PAR";
19"M_B_CPU0_SB_CS_N<0>";
20"M_B_CPU0_SA_RSP<0>";
21"M_B_CPU0_SB_CS_N<1>";
22"M_B_CPU0_SB_PAR";
23"M_B_CPU0_SB_RSP<0>";
24"M_B_CPU0_RESET_N";
25"M_B_CPU0_SB_CA<6>";
26"M_B_CPU0_SB_DQS_DP<9>";
27"M_B_CPU0_SB_DQS_DN<8>";
28"M_B_CPU0_SB_DQS_DN<7>";
29"M_B_CPU0_SA_CA<6>";
30"M_B_CPU0_SB_CA<5>";
31"M_B_CPU0_SA_CA<5>";
32"M_B_CPU0_SB_CA<4>";
33"M_B_CPU0_SA_CA<4>";
34"M_B_CPU0_SB_CA<3>";
35"M_B_CPU0_SA_CA<3>";
36"M_B_CPU0_SB_CA<2>";
37"M_B_CPU0_SA_CA<2>";
38"M_B_CPU0_SB_CA<1>";
39"M_B_CPU0_SA_CA<1>";
40"M_B_CPU0_SB_CA<0>";
41"M_B_CPU0_SA_CA<0>";
42"M_B_CPU0_SB_DQS_DP<8>";
43"M_B_CPU0_SB_DQS_DN<9>";
44"M_B_CPU0_SB_DQS_DP<4>";
45"M_B_CPU0_SA_DQS_DP<9>";
46"M_B_CPU0_SB_DQS_DP<3>";
47"M_B_CPU0_SA_DQS_DP<8>";
48"M_B_CPU0_SB_DQS_DP<2>";
49"M_B_CPU0_SB_DQS_DN<6>";
50"M_B_CPU0_SB_DQS_DP<1>";
51"M_B_CPU0_SB_DQS_DN<5>";
52"M_B_CPU0_SB_DQS_DP<0>";
53"M_B_CPU0_SB_DQS_DN<4>";
54"M_B_CPU0_SA_DQS_DN<9>";
55"M_B_CPU0_SB_DQS_DN<3>";
56"M_B_CPU0_SA_DQS_DN<8>";
57"M_B_CPU0_SB_DQS_DN<2>";
58"M_B_CPU0_SB_DQS_DN<1>";
59"M_B_CPU0_SB_DQS_DN<0>";
60"M_B_CPU0_SB_DQS_DP<7>";
61"M_B_CPU0_SB_DQS_DP<6>";
62"M_B_CPU0_SB_DQS_DP<5>";
63"M_B_CPU0_SA_DQS_DP<7>";
64"M_B_CPU0_SA_DQS_DP<6>";
65"M_B_CPU0_SA_DQS_DP<5>";
66"M_B_CPU0_SA_DQS_DP<4>";
67"M_B_CPU0_SA_DQS_DP<3>";
68"M_B_CPU0_SA_DQS_DN<7>";
69"M_B_CPU0_SA_DQS_DP<2>";
70"M_B_CPU0_SA_DQS_DN<6>";
71"M_B_CPU0_SA_DQS_DP<1>";
72"M_B_CPU0_SA_DQS_DN<5>";
73"M_B_CPU0_SA_DQS_DP<0>";
74"M_B_CPU0_SA_DQS_DN<4>";
75"M_B_CPU0_SA_DQS_DN<3>";
76"M_B_CPU0_SA_DQS_DN<2>";
77"M_B_CPU0_SA_DQS_DN<1>";
78"M_B_CPU0_SA_DQS_DN<0>";
79"M_B_CPU0_SB_CB<7>";
80"M_B_CPU0_SB_CB<6>";
81"M_B_CPU0_SB_CB<5>";
82"M_B_CPU0_SB_CB<4>";
83"M_B_CPU0_SB_CB<3>";
84"M_B_CPU0_SB_CB<2>";
85"M_B_CPU0_SA_CB<7>";
86"M_B_CPU0_SB_CB<1>";
87"M_B_CPU0_SA_CB<6>";
88"M_B_CPU0_SB_CB<0>";
89"M_B_CPU0_SA_CB<5>";
90"M_B_CPU0_SB_DQ<20>";
91"M_B_CPU0_SB_DQ<19>";
92"M_B_CPU0_SA_CB<1>";
93"M_B_CPU0_SA_CB<0>";
94"M_B_CPU0_SB_DQ<29>";
95"M_B_CPU0_SB_DQ<28>";
96"M_B_CPU0_SB_DQ<27>";
97"M_B_CPU0_SB_DQ<26>";
98"M_B_CPU0_SB_DQ<25>";
99"M_B_CPU0_SB_DQ<24>";
100"M_B_CPU0_SB_DQ<23>";
101"M_B_CPU0_SB_DQ<22>";
102"M_B_CPU0_SB_DQ<21>";
103"M_B_CPU0_SB_DQ<31>";
104"M_B_CPU0_SB_DQ<30>";
105"M_B_CPU0_SA_CB<4>";
106"M_B_CPU0_SA_CB<3>";
107"M_B_CPU0_SA_CB<2>";
108"M_B_CPU0_SB_DQ<18>";
109"M_B_CPU0_SB_DQ<9>";
110"M_B_CPU0_SB_DQ<17>";
111"M_B_CPU0_SB_DQ<8>";
112"M_B_CPU0_SB_DQ<16>";
113"M_B_CPU0_SB_DQ<7>";
114"M_B_CPU0_SB_DQ<15>";
115"M_B_CPU0_SB_DQ<6>";
116"M_B_CPU0_SB_DQ<14>";
117"M_B_CPU0_SB_DQ<5>";
118"M_B_CPU0_SB_DQ<13>";
119"M_B_CPU0_SB_DQ<4>";
120"M_B_CPU0_SB_DQ<12>";
121"M_B_CPU0_SB_DQ<3>";
122"M_B_CPU0_SB_DQ<11>";
123"M_B_CPU0_SB_DQ<2>";
124"M_B_CPU0_SB_DQ<10>";
125"M_B_CPU0_SB_DQ<1>";
126"M_B_CPU0_SB_DQ<0>";
127"M_B_CPU0_SA_DQ<24>";
128"M_B_CPU0_SA_DQ<21>";
129"M_B_CPU0_SA_DQ<20>";
130"M_B_CPU0_SA_DQ<31>";
131"M_B_CPU0_SA_DQ<30>";
132"M_B_CPU0_SA_DQ<19>";
133"M_B_CPU0_SA_DQ<18>";
134"M_B_CPU0_SA_DQ<29>";
135"M_B_CPU0_SA_DQ<17>";
136"M_B_CPU0_SA_DQ<28>";
137"M_B_CPU0_SA_DQ<16>";
138"M_B_CPU0_SA_DQ<27>";
139"M_B_CPU0_SA_DQ<15>";
140"M_B_CPU0_SA_DQ<26>";
141"M_B_CPU0_SA_DQ<25>";
142"M_B_CPU0_SA_DQ<23>";
143"M_B_CPU0_SA_DQ<22>";
144"M_B_CPU0_SA_DQ<10>";
145"M_B_CPU0_SA_DQ<9>";
146"M_B_CPU0_SA_DQ<8>";
147"M_B_CPU0_SA_DQ<7>";
148"M_B_CPU0_SA_DQ<6>";
149"M_B_CPU0_SA_DQ<5>";
150"M_B_CPU0_SA_DQ<4>";
151"M_B_CPU0_SA_DQ<3>";
152"M_B_CPU0_SA_DQ<2>";
153"M_B_CPU0_SA_DQ<1>";
154"M_B_CPU0_SA_DQ<14>";
155"M_B_CPU0_SA_DQ<0>";
156"M_B_CPU0_SA_DQ<13>";
157"M_B_CPU0_SA_DQ<12>";
158"M_B_CPU0_SA_DQ<11>";
%"GENOA_SP5"
"2","(-4550,3475)","0","pure_quanta","I171";
;
LOCATION"U25"
$SEC"2"
CDS_SEC"2"
PART_TYPE"SMLF"
MATERIAL"IO"
VALUE"SOCKET6096_13568-001"
PART_NUMBER"DGA^6000030"
CDS_LMAN_SYM_OUTLINE"-650,2550,650,-2550"
CDS_LIB"pure_quanta"
NEEDS_NO_SIZE"TRUE";
"TEST39B"
$PN"BF62"12;
"MBB_DATA20"
$PN"CV63"90;
"MBA_DATA24"
$PN"AC64"127;
"MBB_DATA19"
$PN"CT62"91;
"MB1_CLK_L"
$PN"BG64"0;
"MB1_CLK_H"
$PN"BF63"0;
"MB0_CLK_L"
$PN"BD63"15;
"MB0_CLK_H"
$PN"BC64"14;
"MBB_PAR"
$PN"BL64"22;
"MBA_PAR"
$PN"BC62"18;
"MBB_DQS_H9"
$PN"BV63"26;
"MBA_CHECK1"
$PN"AK62"92;
"MBA_DATA10"
$PN"M63"144;
"MBA_DATA21"
$PN"AB62"128;
"MBB_DQS_H4"
$PN"BY62"44;
"MBB_DQS_L8"
$PN"DC62"27;
"MBA1_CS_L1"
$PN"AV62"0;
"MBA_CHECK0"
$PN"AJ64"93;
"MBA_DATA20"
$PN"AA64"129;
"MBA_DATA31"
$PN"AJ62"130;
"MBA_DQS_H9"
$PN"AN62"45;
"MBB_CA6"
$PN"BK63"25;
"MBB_DQS_H3"
$PN"DB63"46;
"MBB_DQS_L7"
$PN"CU62"28;
"MBA0_CS_L1"
$PN"AW62"17;
"MBA1_CS_L0"
$PN"AU64"0;
"MBA_CA6"
$PN"BB62"29;
"MBA_DATA30"
$PN"AH63"131;
"MBA_DQS_H8"
$PN"AG62"47;
"MBB_CA5"
$PN"BK62"30;
"MBB_DQS_H2"
$PN"CT63"48;
"MBB_DQS_L6"
$PN"CL62"49;
"MBA0_CS_L0"
$PN"AV63"16;
"MBA_CA5"
$PN"BB63"31;
"MBA_DQS_H7"
$PN"AA62"63;
"MBB_CA4"
$PN"BJ62"32;
"MBB_DATA18"
$PN"CR64"108;
"MBB_DATA29"
$PN"DE62"94;
"MBB_DQS_H1"
$PN"CK63"50;
"MBB_DQS_L5"
$PN"CE62"51;
"MBA_CA4"
$PN"BA64"33;
"MBA_DQS_H6"
$PN"R62"64;
"MBB1_RSP_L"
$PN"BR64"0;
"MBB_CA3"
$PN"BJ64"34;
"MBB_DATA9"
$PN"CJ62"109;
"MBB_DATA17"
$PN"CR62"110;
"MBB_DATA28"
$PN"DD63"95;
"MBB_DQS_H0"
$PN"CD63"52;
"MBB_DQS_L4"
$PN"BW62"53;
"MBA_CA3"
$PN"BA62"35;
"MBA_DATA9"
$PN"M62"145;
"MBA_DQS_H5"
$PN"J62"65;
"MBA_DQS_L9"
$PN"AM62"54;
"MBB0_RSP_L"
$PN"BP63"23;
"MBB_CA2"
$PN"BH63"36;
"MBB_CHECK7"
$PN"BV62"79;
"MBB_DATA8"
$PN"CH63"111;
"MBB_DATA16"
$PN"CP63"112;
"MBB_DATA27"
$PN"DB62"96;
"MBB_DQS_L3"
$PN"DC64"55;
"MBA_CA2"
$PN"AY62"37;
"MBA_DATA8"
$PN"L64"146;
"MBA_DQS_H4"
$PN"AL64"66;
"MBA_DQS_L8"
$PN"AF62"56;
"MBB_CA1"
$PN"BH62"38;
"MBB_CHECK6"
$PN"BU64"80;
"MBB_DATA7"
$PN"CH62"113;
"MBB_DATA15"
$PN"CP62"114;
"MBB_DATA26"
$PN"DA64"97;
"MBB_DQS_L2"
$PN"CU64"57;
"MBA_CA1"
$PN"AY63"39;
"MBA_DATA7"
$PN"L62"147;
"MBA_DQS_H3"
$PN"AE64"67;
"MBA_DQS_L7"
$PN"Y62"68;
"MBB_CA0"
$PN"BG62"40;
"MBB_CHECK5"
$PN"BU62"81;
"MBB_DATA6"
$PN"CG64"115;
"MBB_DATA14"
$PN"CN64"116;
"MBB_DATA25"
$PN"DA62"98;
"MBB_DQS_L1"
$PN"CL64"58;
"MBA_CA0"
$PN"AW64"41;
"MBA_DATA6"
$PN"K63"148;
"MBA_DATA19"
$PN"W62"132;
"MBA_DQS_H2"
$PN"W64"69;
"MBA_DQS_L6"
$PN"P62"70;
"MBB_CHECK4"
$PN"BT63"82;
"MBB_DATA5"
$PN"CG62"117;
"MBB_DATA13"
$PN"CN62"118;
"MBB_DATA24"
$PN"CY63"99;
"MBB_DQS_L0"
$PN"CE64"59;
"MBA_DATA5"
$PN"K62"149;
"MBA_DATA18"
$PN"V63"133;
"MBA_DATA29"
$PN"AH62"134;
"MBA_DQS_H1"
$PN"N64"71;
"MBA_DQS_L5"
$PN"H62"72;
"MBB_CHECK3"
$PN"CB62"83;
"MBB_DATA4"
$PN"CF63"119;
"MBB_DATA12"
$PN"CM63"120;
"MBB_DATA23"
$PN"CY62"100;
"MBA1_RSP_L"
$PN"BP62"0;
"MBA_DATA4"
$PN"J64"150;
"MBA_DATA17"
$PN"V62"135;
"MBA_DATA28"
$PN"AG64"136;
"MBA_DQS_H0"
$PN"G64"73;
"MBA_DQS_L4"
$PN"AM63"74;
"MBB_CHECK2"
$PN"CA64"84;
"MBB_DATA3"
$PN"CD62"121;
"MBB_DATA11"
$PN"CK62"122;
"MBB_DATA22"
$PN"CW64"101;
"MBA0_RSP_L"
$PN"BN62"20;
"MBA_CHECK7"
$PN"AR62"85;
"MBA_DATA3"
$PN"G62"151;
"MBA_DATA16"
$PN"U64"137;
"MBA_DATA27"
$PN"AE62"138;
"MBA_DQS_L3"
$PN"AF63"75;
"MBB_CHECK1"
$PN"CA62"86;
"MBB_DATA2"
$PN"CC64"123;
"MBB_DATA10"
$PN"CJ64"124;
"MBB_DATA21"
$PN"CW62"102;
"MBA_CHECK6"
$PN"AP63"87;
"MBA_DATA2"
$PN"F63"152;
"MBA_DATA15"
$PN"U62"139;
"MBA_DATA26"
$PN"AD63"140;
"MBA_DQS_L2"
$PN"Y63"76;
"MBB1_CS_L1"
$PN"BM63"0;
"MBB_CHECK0"
$PN"BY63"88;
"MBB_DATA1"
$PN"CC62"125;
"MBB_DATA31"
$PN"DF62"103;
"MBA_CHECK5"
$PN"AP62"89;
"MBA_DATA1"
$PN"F62"153;
"MBA_DATA14"
$PN"T63"154;
"MBA_DATA25"
$PN"AD62"141;
"MBA_DQS_L1"
$PN"P63"77;
"MBB0_CS_L1"
$PN"BN64"21;
"MBB1_CS_L0"
$PN"BL62"0;
"MBB_DATA0"
$PN"CB63"126;
"MBB_DATA30"
$PN"DE64"104;
"MBB_DQS_H8"
$PN"DD62"42;
"MBA_CHECK4"
$PN"AN64"105;
"MBA_DATA0"
$PN"E64"155;
"MBA_DATA13"
$PN"T62"156;
"MBA_DQS_L0"
$PN"H63"78;
"MBB0_CS_L0"
$PN"BM62"19;
"MBB_DQS_H7"
$PN"CV62"60;
"MBA_CHECK3"
$PN"AL62"106;
"MBA_DATA12"
$PN"R64"157;
"MBA_DATA23"
$PN"AC62"142;
"MBB_DQS_H6"
$PN"CM62"61;
"MBA_CHECK2"
$PN"AK63"107;
"MBA_DATA11"
$PN"N62"158;
"MBA_DATA22"
$PN"AB63"143;
"MBB_DQS_H5"
$PN"CF62"62;
"MBB_DQS_L9"
$PN"BW64"43;
"MB_RESET_L"
$PN"AU62"24;
"MB_ALERT_L"
$PN"AT62"13;
%"TAP"
"1","(-3275,5775)","0","mstr_standard","I173";
;
CDS_LIB"mstr_standard"
BODY_TYPE"PLUMBING"
HDL_TAP"TRUE";
"B \NAC \NWC"1;
"S \NAC"
BN"2"152;
%"TAP"
"1","(-3275,5825)","0","mstr_standard","I174";
;
CDS_LIB"mstr_standard"
BODY_TYPE"PLUMBING"
HDL_TAP"TRUE";
"B \NAC \NWC"1;
"S \NAC"
BN"1"153;
%"TAP"
"1","(-3275,5875)","0","mstr_standard","I175";
;
CDS_LIB"mstr_standard"
BODY_TYPE"PLUMBING"
HDL_TAP"TRUE";
"B \NAC \NWC"1;
"S \NAC"
BN"0"155;
%"TAP"
"1","(-3275,5675)","0","mstr_standard","I176";
;
CDS_LIB"mstr_standard"
BODY_TYPE"PLUMBING"
HDL_TAP"TRUE";
"B \NAC \NWC"1;
"S \NAC"
BN"4"150;
%"TAP"
"1","(-3275,5725)","0","mstr_standard","I177";
;
CDS_LIB"mstr_standard"
BODY_TYPE"PLUMBING"
HDL_TAP"TRUE";
"B \NAC \NWC"1;
"S \NAC"
BN"3"151;
%"TAP"
"1","(-3275,5625)","0","mstr_standard","I178";
;
CDS_LIB"mstr_standard"
BODY_TYPE"PLUMBING"
HDL_TAP"TRUE";
"B \NAC \NWC"1;
"S \NAC"
BN"5"149;
%"TAP"
"1","(-3275,5575)","0","mstr_standard","I179";
;
CDS_LIB"mstr_standard"
BODY_TYPE"PLUMBING"
HDL_TAP"TRUE";
"B \NAC \NWC"1;
"S \NAC"
BN"6"148;
%"TAP"
"1","(-3275,5525)","0","mstr_standard","I180";
;
CDS_LIB"mstr_standard"
BODY_TYPE"PLUMBING"
HDL_TAP"TRUE";
"B \NAC \NWC"1;
"S \NAC"
BN"7"147;
%"TAP"
"1","(-3275,5425)","0","mstr_standard","I181";
;
CDS_LIB"mstr_standard"
BODY_TYPE"PLUMBING"
HDL_TAP"TRUE";
"B \NAC \NWC"1;
"S \NAC"
BN"8"146;
%"TAP"
"1","(-3275,5275)","0","mstr_standard","I182";
;
CDS_LIB"mstr_standard"
BODY_TYPE"PLUMBING"
HDL_TAP"TRUE";
"B \NAC \NWC"1;
"S \NAC"
BN"11"158;
%"TAP"
"1","(-3275,5325)","0","mstr_standard","I183";
;
CDS_LIB"mstr_standard"
BODY_TYPE"PLUMBING"
HDL_TAP"TRUE";
"B \NAC \NWC"1;
"S \NAC"
BN"10"144;
%"TAP"
"1","(-3275,5375)","0","mstr_standard","I184";
;
CDS_LIB"mstr_standard"
BODY_TYPE"PLUMBING"
HDL_TAP"TRUE";
"B \NAC \NWC"1;
"S \NAC"
BN"9"145;
%"TAP"
"1","(-3275,5225)","0","mstr_standard","I185";
;
CDS_LIB"mstr_standard"
BODY_TYPE"PLUMBING"
HDL_TAP"TRUE";
"B \NAC \NWC"1;
"S \NAC"
BN"12"157;
%"TAP"
"1","(-3275,5175)","0","mstr_standard","I186";
;
CDS_LIB"mstr_standard"
BODY_TYPE"PLUMBING"
HDL_TAP"TRUE";
"B \NAC \NWC"1;
"S \NAC"
BN"13"156;
%"TAP"
"1","(-3275,5125)","0","mstr_standard","I187";
;
CDS_LIB"mstr_standard"
BODY_TYPE"PLUMBING"
HDL_TAP"TRUE";
"B \NAC \NWC"1;
"S \NAC"
BN"14"154;
%"TAP"
"1","(-3275,5075)","0","mstr_standard","I188";
;
CDS_LIB"mstr_standard"
BODY_TYPE"PLUMBING"
HDL_TAP"TRUE";
"B \NAC \NWC"1;
"S \NAC"
BN"15"139;
%"TAP"
"1","(-3275,4975)","0","mstr_standard","I189";
;
CDS_LIB"mstr_standard"
BODY_TYPE"PLUMBING"
HDL_TAP"TRUE";
"B \NAC \NWC"1;
"S \NAC"
BN"16"137;
%"TAP"
"1","(-3275,4925)","0","mstr_standard","I190";
;
CDS_LIB"mstr_standard"
BODY_TYPE"PLUMBING"
HDL_TAP"TRUE";
"B \NAC \NWC"1;
"S \NAC"
BN"17"135;
%"TAP"
"1","(-3275,4875)","0","mstr_standard","I191";
;
CDS_LIB"mstr_standard"
BODY_TYPE"PLUMBING"
HDL_TAP"TRUE";
"B \NAC \NWC"1;
"S \NAC"
BN"18"133;
%"TAP"
"1","(-3275,4775)","0","mstr_standard","I192";
;
CDS_LIB"mstr_standard"
BODY_TYPE"PLUMBING"
HDL_TAP"TRUE";
"B \NAC \NWC"1;
"S \NAC"
BN"20"129;
%"TAP"
"1","(-3275,4825)","0","mstr_standard","I193";
;
CDS_LIB"mstr_standard"
BODY_TYPE"PLUMBING"
HDL_TAP"TRUE";
"B \NAC \NWC"1;
"S \NAC"
BN"19"132;
%"TAP"
"1","(-3275,4725)","0","mstr_standard","I194";
;
CDS_LIB"mstr_standard"
BODY_TYPE"PLUMBING"
HDL_TAP"TRUE";
"B \NAC \NWC"1;
"S \NAC"
BN"21"128;
%"TAP"
"1","(-3275,4675)","0","mstr_standard","I195";
;
CDS_LIB"mstr_standard"
BODY_TYPE"PLUMBING"
HDL_TAP"TRUE";
"B \NAC \NWC"1;
"S \NAC"
BN"22"143;
%"TAP"
"1","(-3275,4625)","0","mstr_standard","I196";
;
CDS_LIB"mstr_standard"
BODY_TYPE"PLUMBING"
HDL_TAP"TRUE";
"B \NAC \NWC"1;
"S \NAC"
BN"23"142;
%"TAP"
"1","(-3275,4525)","0","mstr_standard","I197";
;
CDS_LIB"mstr_standard"
BODY_TYPE"PLUMBING"
HDL_TAP"TRUE";
"B \NAC \NWC"1;
"S \NAC"
BN"24"127;
%"TAP"
"1","(-3275,4475)","0","mstr_standard","I198";
;
CDS_LIB"mstr_standard"
BODY_TYPE"PLUMBING"
HDL_TAP"TRUE";
"B \NAC \NWC"1;
"S \NAC"
BN"25"141;
%"TAP"
"1","(-3275,4425)","0","mstr_standard","I199";
;
CDS_LIB"mstr_standard"
BODY_TYPE"PLUMBING"
HDL_TAP"TRUE";
"B \NAC \NWC"1;
"S \NAC"
BN"26"140;
%"TAP"
"1","(-3275,4375)","0","mstr_standard","I200";
;
CDS_LIB"mstr_standard"
BODY_TYPE"PLUMBING"
HDL_TAP"TRUE";
"B \NAC \NWC"1;
"S \NAC"
BN"27"138;
%"TAP"
"1","(-3275,4275)","0","mstr_standard","I201";
;
CDS_LIB"mstr_standard"
BODY_TYPE"PLUMBING"
HDL_TAP"TRUE";
"B \NAC \NWC"1;
"S \NAC"
BN"29"134;
%"TAP"
"1","(-3275,4225)","0","mstr_standard","I202";
;
CDS_LIB"mstr_standard"
BODY_TYPE"PLUMBING"
HDL_TAP"TRUE";
"B \NAC \NWC"1;
"S \NAC"
BN"30"131;
%"TAP"
"1","(-3275,4325)","0","mstr_standard","I203";
;
CDS_LIB"mstr_standard"
BODY_TYPE"PLUMBING"
HDL_TAP"TRUE";
"B \NAC \NWC"1;
"S \NAC"
BN"28"136;
%"TAP"
"1","(-3275,4175)","0","mstr_standard","I204";
;
CDS_LIB"mstr_standard"
BODY_TYPE"PLUMBING"
HDL_TAP"TRUE";
"B \NAC \NWC"1;
"S \NAC"
BN"31"130;
%"TAP"
"1","(-3275,3975)","0","mstr_standard","I207";
;
CDS_LIB"mstr_standard"
BODY_TYPE"PLUMBING"
HDL_TAP"TRUE";
"B \NAC \NWC"2;
"S \NAC"
BN"2"123;
%"TAP"
"1","(-3275,4025)","0","mstr_standard","I208";
;
CDS_LIB"mstr_standard"
BODY_TYPE"PLUMBING"
HDL_TAP"TRUE";
"B \NAC \NWC"2;
"S \NAC"
BN"1"125;
%"TAP"
"1","(-3275,4075)","0","mstr_standard","I209";
;
CDS_LIB"mstr_standard"
BODY_TYPE"PLUMBING"
HDL_TAP"TRUE";
"B \NAC \NWC"2;
"S \NAC"
BN"0"126;
%"TAP"
"1","(-3275,3925)","0","mstr_standard","I210";
;
CDS_LIB"mstr_standard"
BODY_TYPE"PLUMBING"
HDL_TAP"TRUE";
"B \NAC \NWC"2;
"S \NAC"
BN"3"121;
%"TAP"
"1","(-3275,3875)","0","mstr_standard","I211";
;
CDS_LIB"mstr_standard"
BODY_TYPE"PLUMBING"
HDL_TAP"TRUE";
"B \NAC \NWC"2;
"S \NAC"
BN"4"119;
%"TAP"
"1","(-3275,3825)","0","mstr_standard","I212";
;
CDS_LIB"mstr_standard"
BODY_TYPE"PLUMBING"
HDL_TAP"TRUE";
"B \NAC \NWC"2;
"S \NAC"
BN"5"117;
%"TAP"
"1","(-3275,3725)","0","mstr_standard","I213";
;
CDS_LIB"mstr_standard"
BODY_TYPE"PLUMBING"
HDL_TAP"TRUE";
"B \NAC \NWC"2;
"S \NAC"
BN"7"113;
%"TAP"
"1","(-3275,3775)","0","mstr_standard","I214";
;
CDS_LIB"mstr_standard"
BODY_TYPE"PLUMBING"
HDL_TAP"TRUE";
"B \NAC \NWC"2;
"S \NAC"
BN"6"115;
%"TAP"
"1","(-3275,3625)","0","mstr_standard","I215";
;
CDS_LIB"mstr_standard"
BODY_TYPE"PLUMBING"
HDL_TAP"TRUE";
"B \NAC \NWC"2;
"S \NAC"
BN"8"111;
%"TAP"
"1","(-3275,3475)","0","mstr_standard","I216";
;
CDS_LIB"mstr_standard"
BODY_TYPE"PLUMBING"
HDL_TAP"TRUE";
"B \NAC \NWC"2;
"S \NAC"
BN"11"122;
%"TAP"
"1","(-3275,3575)","0","mstr_standard","I217";
;
CDS_LIB"mstr_standard"
BODY_TYPE"PLUMBING"
HDL_TAP"TRUE";
"B \NAC \NWC"2;
"S \NAC"
BN"9"109;
%"TAP"
"1","(-3275,3525)","0","mstr_standard","I218";
;
CDS_LIB"mstr_standard"
BODY_TYPE"PLUMBING"
HDL_TAP"TRUE";
"B \NAC \NWC"2;
"S \NAC"
BN"10"124;
%"TAP"
"1","(-3275,3425)","0","mstr_standard","I219";
;
CDS_LIB"mstr_standard"
BODY_TYPE"PLUMBING"
HDL_TAP"TRUE";
"B \NAC \NWC"2;
"S \NAC"
BN"12"120;
%"TAP"
"1","(-3275,3375)","0","mstr_standard","I220";
;
CDS_LIB"mstr_standard"
BODY_TYPE"PLUMBING"
HDL_TAP"TRUE";
"B \NAC \NWC"2;
"S \NAC"
BN"13"118;
%"TAP"
"1","(-3275,3275)","0","mstr_standard","I221";
;
CDS_LIB"mstr_standard"
BODY_TYPE"PLUMBING"
HDL_TAP"TRUE";
"B \NAC \NWC"2;
"S \NAC"
BN"15"114;
%"TAP"
"1","(-3275,3325)","0","mstr_standard","I222";
;
CDS_LIB"mstr_standard"
BODY_TYPE"PLUMBING"
HDL_TAP"TRUE";
"B \NAC \NWC"2;
"S \NAC"
BN"14"116;
%"TAP"
"1","(-3275,3175)","0","mstr_standard","I223";
;
CDS_LIB"mstr_standard"
BODY_TYPE"PLUMBING"
HDL_TAP"TRUE";
"B \NAC \NWC"2;
"S \NAC"
BN"16"112;
%"TAP"
"1","(-3275,3125)","0","mstr_standard","I224";
;
CDS_LIB"mstr_standard"
BODY_TYPE"PLUMBING"
HDL_TAP"TRUE";
"B \NAC \NWC"2;
"S \NAC"
BN"17"110;
%"TAP"
"1","(-3275,3075)","0","mstr_standard","I225";
;
CDS_LIB"mstr_standard"
BODY_TYPE"PLUMBING"
HDL_TAP"TRUE";
"B \NAC \NWC"2;
"S \NAC"
BN"18"108;
%"TAP"
"1","(-3275,2975)","0","mstr_standard","I226";
;
CDS_LIB"mstr_standard"
BODY_TYPE"PLUMBING"
HDL_TAP"TRUE";
"B \NAC \NWC"2;
"S \NAC"
BN"20"90;
%"TAP"
"1","(-3275,3025)","0","mstr_standard","I227";
;
CDS_LIB"mstr_standard"
BODY_TYPE"PLUMBING"
HDL_TAP"TRUE";
"B \NAC \NWC"2;
"S \NAC"
BN"19"91;
%"TAP"
"1","(-3275,2825)","0","mstr_standard","I228";
;
CDS_LIB"mstr_standard"
BODY_TYPE"PLUMBING"
HDL_TAP"TRUE";
"B \NAC \NWC"2;
"S \NAC"
BN"23"100;
%"TAP"
"1","(-3275,2925)","0","mstr_standard","I229";
;
CDS_LIB"mstr_standard"
BODY_TYPE"PLUMBING"
HDL_TAP"TRUE";
"B \NAC \NWC"2;
"S \NAC"
BN"21"102;
%"TAP"
"1","(-3275,2875)","0","mstr_standard","I230";
;
CDS_LIB"mstr_standard"
BODY_TYPE"PLUMBING"
HDL_TAP"TRUE";
"B \NAC \NWC"2;
"S \NAC"
BN"22"101;
%"TAP"
"1","(-3275,2725)","0","mstr_standard","I231";
;
CDS_LIB"mstr_standard"
BODY_TYPE"PLUMBING"
HDL_TAP"TRUE";
"B \NAC \NWC"2;
"S \NAC"
BN"24"99;
%"TAP"
"1","(-3275,2625)","0","mstr_standard","I232";
;
CDS_LIB"mstr_standard"
BODY_TYPE"PLUMBING"
HDL_TAP"TRUE";
"B \NAC \NWC"2;
"S \NAC"
BN"26"97;
%"TAP"
"1","(-3275,2675)","0","mstr_standard","I233";
;
CDS_LIB"mstr_standard"
BODY_TYPE"PLUMBING"
HDL_TAP"TRUE";
"B \NAC \NWC"2;
"S \NAC"
BN"25"98;
%"TAP"
"1","(-3275,2575)","0","mstr_standard","I234";
;
CDS_LIB"mstr_standard"
BODY_TYPE"PLUMBING"
HDL_TAP"TRUE";
"B \NAC \NWC"2;
"S \NAC"
BN"27"96;
%"TAP"
"1","(-3275,2525)","0","mstr_standard","I235";
;
CDS_LIB"mstr_standard"
BODY_TYPE"PLUMBING"
HDL_TAP"TRUE";
"B \NAC \NWC"2;
"S \NAC"
BN"28"95;
%"TAP"
"1","(-3275,2475)","0","mstr_standard","I236";
;
CDS_LIB"mstr_standard"
BODY_TYPE"PLUMBING"
HDL_TAP"TRUE";
"B \NAC \NWC"2;
"S \NAC"
BN"29"94;
%"TAP"
"1","(-3275,2425)","0","mstr_standard","I237";
;
CDS_LIB"mstr_standard"
BODY_TYPE"PLUMBING"
HDL_TAP"TRUE";
"B \NAC \NWC"2;
"S \NAC"
BN"30"104;
%"TAP"
"1","(-3275,2375)","0","mstr_standard","I238";
;
CDS_LIB"mstr_standard"
BODY_TYPE"PLUMBING"
HDL_TAP"TRUE";
"B \NAC \NWC"2;
"S \NAC"
BN"31"103;
%"TAP"
"1","(-3275,2275)","0","mstr_standard","I239";
;
CDS_LIB"mstr_standard"
BODY_TYPE"PLUMBING"
HDL_TAP"TRUE";
"B \NAC \NWC"3;
"S \NAC"
BN"0"93;
%"TAP"
"1","(-3275,2225)","0","mstr_standard","I240";
;
CDS_LIB"mstr_standard"
BODY_TYPE"PLUMBING"
HDL_TAP"TRUE";
"B \NAC \NWC"3;
"S \NAC"
BN"1"92;
%"TAP"
"1","(-3275,2075)","0","mstr_standard","I241";
;
CDS_LIB"mstr_standard"
BODY_TYPE"PLUMBING"
HDL_TAP"TRUE";
"B \NAC \NWC"3;
"S \NAC"
BN"4"105;
%"TAP"
"1","(-3275,2175)","0","mstr_standard","I242";
;
CDS_LIB"mstr_standard"
BODY_TYPE"PLUMBING"
HDL_TAP"TRUE";
"B \NAC \NWC"3;
"S \NAC"
BN"2"107;
%"TAP"
"1","(-3275,2125)","0","mstr_standard","I243";
;
CDS_LIB"mstr_standard"
BODY_TYPE"PLUMBING"
HDL_TAP"TRUE";
"B \NAC \NWC"3;
"S \NAC"
BN"3"106;
%"TAP"
"1","(-3275,1925)","0","mstr_standard","I245";
;
CDS_LIB"mstr_standard"
BODY_TYPE"PLUMBING"
HDL_TAP"TRUE";
"B \NAC \NWC"3;
"S \NAC"
BN"7"85;
%"TAP"
"1","(-3275,2025)","0","mstr_standard","I246";
;
CDS_LIB"mstr_standard"
BODY_TYPE"PLUMBING"
HDL_TAP"TRUE";
"B \NAC \NWC"3;
"S \NAC"
BN"5"89;
%"TAP"
"1","(-3275,1975)","0","mstr_standard","I247";
;
CDS_LIB"mstr_standard"
BODY_TYPE"PLUMBING"
HDL_TAP"TRUE";
"B \NAC \NWC"3;
"S \NAC"
BN"6"87;
%"TAP"
"1","(-3275,1825)","0","mstr_standard","I248";
;
CDS_LIB"mstr_standard"
BODY_TYPE"PLUMBING"
HDL_TAP"TRUE";
"B \NAC \NWC"4;
"S \NAC"
BN"0"88;
%"TAP"
"1","(-3275,1775)","0","mstr_standard","I249";
;
CDS_LIB"mstr_standard"
BODY_TYPE"PLUMBING"
HDL_TAP"TRUE";
"B \NAC \NWC"4;
"S \NAC"
BN"1"86;
%"TAP"
"1","(-3275,1725)","0","mstr_standard","I250";
;
CDS_LIB"mstr_standard"
BODY_TYPE"PLUMBING"
HDL_TAP"TRUE";
"B \NAC \NWC"4;
"S \NAC"
BN"2"84;
%"TAP"
"1","(-3275,1675)","0","mstr_standard","I251";
;
CDS_LIB"mstr_standard"
BODY_TYPE"PLUMBING"
HDL_TAP"TRUE";
"B \NAC \NWC"4;
"S \NAC"
BN"3"83;
%"TAP"
"1","(-3275,1625)","0","mstr_standard","I252";
;
CDS_LIB"mstr_standard"
BODY_TYPE"PLUMBING"
HDL_TAP"TRUE";
"B \NAC \NWC"4;
"S \NAC"
BN"4"82;
%"TAP"
"1","(-3275,1575)","0","mstr_standard","I253";
;
CDS_LIB"mstr_standard"
BODY_TYPE"PLUMBING"
HDL_TAP"TRUE";
"B \NAC \NWC"4;
"S \NAC"
BN"5"81;
%"TAP"
"1","(-3275,1475)","0","mstr_standard","I254";
;
CDS_LIB"mstr_standard"
BODY_TYPE"PLUMBING"
HDL_TAP"TRUE";
"B \NAC \NWC"4;
"S \NAC"
BN"7"79;
%"TAP"
"1","(-3275,1525)","0","mstr_standard","I255";
;
CDS_LIB"mstr_standard"
BODY_TYPE"PLUMBING"
HDL_TAP"TRUE";
"B \NAC \NWC"4;
"S \NAC"
BN"6"80;
%"TAP"
"1","(-5700,5875)","2","mstr_standard","I256";
;
CDS_LIB"mstr_standard"
BODY_TYPE"PLUMBING"
HDL_TAP"TRUE";
"B \NAC \NWC"5;
"S \NAC"
BN"0"73;
%"TAP"
"1","(-5700,5775)","2","mstr_standard","I257";
;
CDS_LIB"mstr_standard"
BODY_TYPE"PLUMBING"
HDL_TAP"TRUE";
"B \NAC \NWC"5;
"S \NAC"
BN"1"71;
%"TAP"
"1","(-5700,5675)","2","mstr_standard","I258";
;
CDS_LIB"mstr_standard"
BODY_TYPE"PLUMBING"
HDL_TAP"TRUE";
"B \NAC \NWC"5;
"S \NAC"
BN"2"69;
%"TAP"
"1","(-5900,5725)","2","mstr_standard","I259";
;
CDS_LIB"mstr_standard"
BODY_TYPE"PLUMBING"
HDL_TAP"TRUE";
"B \NAC \NWC"9;
"S \NAC"
BN"1"77;
%"TAP"
"1","(-5900,5825)","2","mstr_standard","I260";
;
CDS_LIB"mstr_standard"
BODY_TYPE"PLUMBING"
HDL_TAP"TRUE";
"B \NAC \NWC"9;
"S \NAC"
BN"0"78;
%"TAP"
"1","(-5700,5575)","2","mstr_standard","I261";
;
CDS_LIB"mstr_standard"
BODY_TYPE"PLUMBING"
HDL_TAP"TRUE";
"B \NAC \NWC"5;
"S \NAC"
BN"3"67;
%"TAP"
"1","(-5700,5375)","2","mstr_standard","I262";
;
CDS_LIB"mstr_standard"
BODY_TYPE"PLUMBING"
HDL_TAP"TRUE";
"B \NAC \NWC"5;
"S \NAC"
BN"5"65;
%"TAP"
"1","(-5700,5475)","2","mstr_standard","I263";
;
CDS_LIB"mstr_standard"
BODY_TYPE"PLUMBING"
HDL_TAP"TRUE";
"B \NAC \NWC"5;
"S \NAC"
BN"4"66;
%"TAP"
"1","(-5900,5425)","2","mstr_standard","I264";
;
CDS_LIB"mstr_standard"
BODY_TYPE"PLUMBING"
HDL_TAP"TRUE";
"B \NAC \NWC"9;
"S \NAC"
BN"4"74;
%"TAP"
"1","(-5900,5625)","2","mstr_standard","I265";
;
CDS_LIB"mstr_standard"
BODY_TYPE"PLUMBING"
HDL_TAP"TRUE";
"B \NAC \NWC"9;
"S \NAC"
BN"2"76;
%"TAP"
"1","(-5900,5525)","2","mstr_standard","I266";
;
CDS_LIB"mstr_standard"
BODY_TYPE"PLUMBING"
HDL_TAP"TRUE";
"B \NAC \NWC"9;
"S \NAC"
BN"3"75;
%"TAP"
"1","(-5700,5175)","2","mstr_standard","I267";
;
CDS_LIB"mstr_standard"
BODY_TYPE"PLUMBING"
HDL_TAP"TRUE";
"B \NAC \NWC"5;
"S \NAC"
BN"7"63;
%"TAP"
"1","(-5700,5275)","2","mstr_standard","I268";
;
CDS_LIB"mstr_standard"
BODY_TYPE"PLUMBING"
HDL_TAP"TRUE";
"B \NAC \NWC"5;
"S \NAC"
BN"6"64;
%"TAP"
"1","(-5900,5325)","2","mstr_standard","I269";
;
CDS_LIB"mstr_standard"
BODY_TYPE"PLUMBING"
HDL_TAP"TRUE";
"B \NAC \NWC"9;
"S \NAC"
BN"5"72;
%"TAP"
"1","(-5900,5225)","2","mstr_standard","I270";
;
CDS_LIB"mstr_standard"
BODY_TYPE"PLUMBING"
HDL_TAP"TRUE";
"B \NAC \NWC"9;
"S \NAC"
BN"6"70;
%"TAP"
"1","(-5900,5125)","2","mstr_standard","I271";
;
CDS_LIB"mstr_standard"
BODY_TYPE"PLUMBING"
HDL_TAP"TRUE";
"B \NAC \NWC"9;
"S \NAC"
BN"7"68;
%"TAP"
"1","(-5700,4975)","2","mstr_standard","I272";
;
CDS_LIB"mstr_standard"
BODY_TYPE"PLUMBING"
HDL_TAP"TRUE";
"B \NAC \NWC"5;
"S \NAC"
BN"9"45;
%"TAP"
"1","(-5700,5075)","2","mstr_standard","I273";
;
CDS_LIB"mstr_standard"
BODY_TYPE"PLUMBING"
HDL_TAP"TRUE";
"B \NAC \NWC"5;
"S \NAC"
BN"8"47;
%"TAP"
"1","(-5900,5025)","2","mstr_standard","I274";
;
CDS_LIB"mstr_standard"
BODY_TYPE"PLUMBING"
HDL_TAP"TRUE";
"B \NAC \NWC"9;
"S \NAC"
BN"8"56;
%"TAP"
"1","(-5900,4925)","2","mstr_standard","I275";
;
CDS_LIB"mstr_standard"
BODY_TYPE"PLUMBING"
HDL_TAP"TRUE";
"B \NAC \NWC"9;
"S \NAC"
BN"9"54;
%"TAP"
"1","(-5700,4625)","2","mstr_standard","I276";
;
CDS_LIB"mstr_standard"
BODY_TYPE"PLUMBING"
HDL_TAP"TRUE";
"B \NAC \NWC"6;
"S \NAC"
BN"2"48;
%"TAP"
"1","(-5700,4825)","2","mstr_standard","I277";
;
CDS_LIB"mstr_standard"
BODY_TYPE"PLUMBING"
HDL_TAP"TRUE";
"B \NAC \NWC"6;
"S \NAC"
BN"0"52;
%"TAP"
"1","(-5700,4725)","2","mstr_standard","I278";
;
CDS_LIB"mstr_standard"
BODY_TYPE"PLUMBING"
HDL_TAP"TRUE";
"B \NAC \NWC"6;
"S \NAC"
BN"1"50;
%"TAP"
"1","(-5900,4675)","2","mstr_standard","I279";
;
CDS_LIB"mstr_standard"
BODY_TYPE"PLUMBING"
HDL_TAP"TRUE";
"B \NAC \NWC"10;
"S \NAC"
BN"1"58;
%"TAP"
"1","(-5900,4775)","2","mstr_standard","I280";
;
CDS_LIB"mstr_standard"
BODY_TYPE"PLUMBING"
HDL_TAP"TRUE";
"B \NAC \NWC"10;
"S \NAC"
BN"0"59;
%"TAP"
"1","(-5700,4525)","2","mstr_standard","I281";
;
CDS_LIB"mstr_standard"
BODY_TYPE"PLUMBING"
HDL_TAP"TRUE";
"B \NAC \NWC"6;
"S \NAC"
BN"3"46;
%"TAP"
"1","(-5700,4425)","2","mstr_standard","I282";
;
CDS_LIB"mstr_standard"
BODY_TYPE"PLUMBING"
HDL_TAP"TRUE";
"B \NAC \NWC"6;
"S \NAC"
BN"4"44;
%"TAP"
"1","(-5900,4575)","2","mstr_standard","I283";
;
CDS_LIB"mstr_standard"
BODY_TYPE"PLUMBING"
HDL_TAP"TRUE";
"B \NAC \NWC"10;
"S \NAC"
BN"2"57;
%"TAP"
"1","(-5900,4475)","2","mstr_standard","I284";
;
CDS_LIB"mstr_standard"
BODY_TYPE"PLUMBING"
HDL_TAP"TRUE";
"B \NAC \NWC"10;
"S \NAC"
BN"3"55;
%"TAP"
"1","(-5900,4375)","2","mstr_standard","I285";
;
CDS_LIB"mstr_standard"
BODY_TYPE"PLUMBING"
HDL_TAP"TRUE";
"B \NAC \NWC"10;
"S \NAC"
BN"4"53;
%"TAP"
"1","(-5700,4225)","2","mstr_standard","I286";
;
CDS_LIB"mstr_standard"
BODY_TYPE"PLUMBING"
HDL_TAP"TRUE";
"B \NAC \NWC"6;
"S \NAC"
BN"6"61;
%"TAP"
"1","(-5700,4125)","2","mstr_standard","I287";
;
CDS_LIB"mstr_standard"
BODY_TYPE"PLUMBING"
HDL_TAP"TRUE";
"B \NAC \NWC"6;
"S \NAC"
BN"7"60;
%"TAP"
"1","(-5700,4325)","2","mstr_standard","I288";
;
CDS_LIB"mstr_standard"
BODY_TYPE"PLUMBING"
HDL_TAP"TRUE";
"B \NAC \NWC"6;
"S \NAC"
BN"5"62;
%"TAP"
"1","(-5900,4175)","2","mstr_standard","I289";
;
CDS_LIB"mstr_standard"
BODY_TYPE"PLUMBING"
HDL_TAP"TRUE";
"B \NAC \NWC"10;
"S \NAC"
BN"6"49;
%"TAP"
"1","(-5900,4275)","2","mstr_standard","I290";
;
CDS_LIB"mstr_standard"
BODY_TYPE"PLUMBING"
HDL_TAP"TRUE";
"B \NAC \NWC"10;
"S \NAC"
BN"5"51;
%"TAP"
"1","(-5700,4025)","2","mstr_standard","I295";
;
CDS_LIB"mstr_standard"
BODY_TYPE"PLUMBING"
HDL_TAP"TRUE";
"B \NAC \NWC"6;
"S \NAC"
BN"8"42;
%"TAP"
"1","(-5700,3925)","2","mstr_standard","I296";
;
CDS_LIB"mstr_standard"
BODY_TYPE"PLUMBING"
HDL_TAP"TRUE";
"B \NAC \NWC"6;
"S \NAC"
BN"9"26;
%"TAP"
"1","(-5900,3875)","2","mstr_standard","I297";
;
CDS_LIB"mstr_standard"
BODY_TYPE"PLUMBING"
HDL_TAP"TRUE";
"B \NAC \NWC"10;
"S \NAC"
BN"9"43;
%"TAP"
"1","(-5900,3975)","2","mstr_standard","I298";
;
CDS_LIB"mstr_standard"
BODY_TYPE"PLUMBING"
HDL_TAP"TRUE";
"B \NAC \NWC"10;
"S \NAC"
BN"8"27;
%"TAP"
"1","(-5900,4075)","2","mstr_standard","I299";
;
CDS_LIB"mstr_standard"
BODY_TYPE"PLUMBING"
HDL_TAP"TRUE";
"B \NAC \NWC"10;
"S \NAC"
BN"7"28;
%"TAP"
"1","(-5900,3725)","2","mstr_standard","I300";
;
CDS_LIB"mstr_standard"
BODY_TYPE"PLUMBING"
HDL_TAP"TRUE";
"B \NAC \NWC"7;
"S \NAC"
BN"0"41;
%"TAP"
"1","(-5900,3675)","2","mstr_standard","I301";
;
CDS_LIB"mstr_standard"
BODY_TYPE"PLUMBING"
HDL_TAP"TRUE";
"B \NAC \NWC"7;
"S \NAC"
BN"1"39;
%"TAP"
"1","(-5900,3625)","2","mstr_standard","I302";
;
CDS_LIB"mstr_standard"
BODY_TYPE"PLUMBING"
HDL_TAP"TRUE";
"B \NAC \NWC"7;
"S \NAC"
BN"2"37;
%"TAP"
"1","(-5900,3525)","2","mstr_standard","I303";
;
CDS_LIB"mstr_standard"
BODY_TYPE"PLUMBING"
HDL_TAP"TRUE";
"B \NAC \NWC"7;
"S \NAC"
BN"4"33;
%"TAP"
"1","(-5900,3475)","2","mstr_standard","I304";
;
CDS_LIB"mstr_standard"
BODY_TYPE"PLUMBING"
HDL_TAP"TRUE";
"B \NAC \NWC"7;
"S \NAC"
BN"5"31;
%"TAP"
"1","(-5900,3575)","2","mstr_standard","I305";
;
CDS_LIB"mstr_standard"
BODY_TYPE"PLUMBING"
HDL_TAP"TRUE";
"B \NAC \NWC"7;
"S \NAC"
BN"3"35;
%"TAP"
"1","(-5900,3425)","2","mstr_standard","I306";
;
CDS_LIB"mstr_standard"
BODY_TYPE"PLUMBING"
HDL_TAP"TRUE";
"B \NAC \NWC"7;
"S \NAC"
BN"6"29;
%"TAP"
"1","(-5900,3325)","2","mstr_standard","I307";
;
CDS_LIB"mstr_standard"
BODY_TYPE"PLUMBING"
HDL_TAP"TRUE";
"B \NAC \NWC"8;
"S \NAC"
BN"0"40;
%"TAP"
"1","(-5900,3275)","2","mstr_standard","I308";
;
CDS_LIB"mstr_standard"
BODY_TYPE"PLUMBING"
HDL_TAP"TRUE";
"B \NAC \NWC"8;
"S \NAC"
BN"1"38;
%"TAP"
"1","(-5900,3225)","2","mstr_standard","I309";
;
CDS_LIB"mstr_standard"
BODY_TYPE"PLUMBING"
HDL_TAP"TRUE";
"B \NAC \NWC"8;
"S \NAC"
BN"2"36;
%"TAP"
"1","(-5900,3175)","2","mstr_standard","I310";
;
CDS_LIB"mstr_standard"
BODY_TYPE"PLUMBING"
HDL_TAP"TRUE";
"B \NAC \NWC"8;
"S \NAC"
BN"3"34;
%"TAP"
"1","(-5900,3125)","2","mstr_standard","I311";
;
CDS_LIB"mstr_standard"
BODY_TYPE"PLUMBING"
HDL_TAP"TRUE";
"B \NAC \NWC"8;
"S \NAC"
BN"4"32;
%"TAP"
"1","(-5900,3075)","2","mstr_standard","I312";
;
CDS_LIB"mstr_standard"
BODY_TYPE"PLUMBING"
HDL_TAP"TRUE";
"B \NAC \NWC"8;
"S \NAC"
BN"5"30;
%"TAP"
"1","(-5900,3025)","2","mstr_standard","I313";
;
CDS_LIB"mstr_standard"
BODY_TYPE"PLUMBING"
HDL_TAP"TRUE";
"B \NAC \NWC"8;
"S \NAC"
BN"6"25;
%"Q_RES"
"1","(-6825,2025)","0","pure_quanta","I327";
;
LOCATION"R376"
$SEC"1"
CDS_SEC"1"
TOLERANCE"1%"
VALUE"15   "
PART_NUMBER"CS01502FB11"
PACK_TYPE"0402LF"
CDS_LIB"pure_quanta"
WATTAGE"1/16W"
MATERIAL"CHIP";
"B"
$PN"2"13;
"A"
$PN"1"11;
END.
